(kicad_pcb
	(version 20260206)
	(generator "pcbnew")
	(generator_version "10.0")
	(general
		(thickness 1.6)
		(legacy_teardrops no)
	)
	(paper "A4")
	(title_block
		(title "03242023_DA0F0TMBIJ0_F0T_Motherboard_J_brd_V01_OCP.brd")
		(comment 1 "Grand Teton / footprints 3425-3429 of 6105")
	)
	(layers
		(0 "F.Cu" signal "TOP")
		(4 "In1.Cu" signal "GND")
		(6 "In2.Cu" signal "IN1")
		(8 "In3.Cu" signal "GND1")
		(10 "In4.Cu" signal "IN2")
		(12 "In5.Cu" signal "GND2")
		(14 "In6.Cu" signal "IN3")
		(16 "In7.Cu" signal "GND3")
		(18 "In8.Cu" signal "VCC")
		(20 "In9.Cu" signal "VCC1")
		(22 "In10.Cu" signal "GND4")
		(24 "In11.Cu" signal "IN4")
		(26 "In12.Cu" signal "GND5")
		(28 "In13.Cu" signal "IN5")
		(30 "In14.Cu" signal "GND6")
		(32 "In15.Cu" signal "IN6")
		(34 "In16.Cu" signal "GND7")
		(2 "B.Cu" signal "BOTTOM")
		(9 "F.Adhes" user "F.Adhesive")
		(11 "B.Adhes" user "B.Adhesive")
		(13 "F.Paste" user "Package Geometry/Pastemask Top")
		(15 "B.Paste" user "Package Geometry/Pastemask Bottom")
		(5 "F.SilkS" user "Ref Des/Silkscreen Top")
		(7 "B.SilkS" user "Ref Des/Silkscreen Bottom")
		(1 "F.Mask" user "Board Geometry/Soldermask Top")
		(3 "B.Mask" user "Board Geometry/Soldermask Bottom")
		(17 "Dwgs.User" user "User.Drawings")
		(19 "Cmts.User" user "User.Comments")
		(21 "Eco1.User" user "User.Eco1")
		(23 "Eco2.User" user "User.Eco2")
		(25 "Edge.Cuts" user "Board Geometry/Outline")
		(27 "Margin" user)
		(31 "F.CrtYd" user "Package Geometry/Place Bound Top")
		(29 "B.CrtYd" user "Package Geometry/Place Bound Bottom")
		(35 "F.Fab" user "Ref Des/Assembly Top")
		(33 "B.Fab" user "Ref Des/Assembly Bottom")
	)
	(footprint ""
		(layer "F.Cu")
		(at 205.397608 -400.759422)
		(property "Reference" "PR3919"
			(at 0 0 0)
			(layer "F.SilkS")
			(hide yes)
			(effects
				(font
					(size 1.27 1.27)
				)
			)
		)
		(property "Value" ""
			(at 0 0 0)
			(layer "F.Fab")
			(effects
				(font
					(size 1.27 1.27)
				)
			)
		)
		(duplicate_pad_numbers_are_jumpers no)
		(fp_line
			(start -0.7874 -0.4064)
			(end 0.7874 -0.4064)
			(stroke
				(width 0.1524)
				(type default)
			)
			(layer "F.SilkS")
		)
		(fp_line
			(start -0.7874 0.4064)
			(end -0.7874 -0.4064)
			(stroke
				(width 0.1524)
				(type default)
			)
			(layer "F.SilkS")
		)
		(fp_line
			(start 0.7874 -0.4064)
			(end 0.7874 0.4064)
			(stroke
				(width 0.1524)
				(type default)
			)
			(layer "F.SilkS")
		)
		(fp_line
			(start 0.7874 0.4064)
			(end -0.7874 0.4064)
			(stroke
				(width 0.1524)
				(type default)
			)
			(layer "F.SilkS")
		)
		(fp_line
			(start -0.67945 -0.305054)
			(end -0.12065 -0.305054)
			(stroke
				(width 0.1)
				(type default)
			)
			(layer "F.Fab")
		)
		(fp_line
			(start -0.67945 0.3048)
			(end -0.67945 -0.305054)
			(stroke
				(width 0.1)
				(type default)
			)
			(layer "F.Fab")
		)
		(fp_line
			(start -0.12065 -0.305054)
			(end -0.12065 -0.2794)
			(stroke
				(width 0.1)
				(type default)
			)
			(layer "F.Fab")
		)
		(fp_line
			(start -0.12065 -0.2794)
			(end 0.12065 -0.2794)
			(stroke
				(width 0.1)
				(type default)
			)
			(layer "F.Fab")
		)
		(fp_line
			(start -0.12065 0.2794)
			(end -0.12065 0.3048)
			(stroke
				(width 0.1)
				(type default)
			)
			(layer "F.Fab")
		)
		(fp_line
			(start -0.12065 0.3048)
			(end -0.67945 0.3048)
			(stroke
				(width 0.1)
				(type default)
			)
			(layer "F.Fab")
		)
		(fp_line
			(start 0.120396 0.2794)
			(end -0.12065 0.2794)
			(stroke
				(width 0.1)
				(type default)
			)
			(layer "F.Fab")
		)
		(fp_line
			(start 0.120396 0.3048)
			(end 0.120396 0.2794)
			(stroke
				(width 0.1)
				(type default)
			)
			(layer "F.Fab")
		)
		(fp_line
			(start 0.12065 -0.3048)
			(end 0.67945 -0.3048)
			(stroke
				(width 0.1)
				(type default)
			)
			(layer "F.Fab")
		)
		(fp_line
			(start 0.12065 -0.2794)
			(end 0.12065 -0.3048)
			(stroke
				(width 0.1)
				(type default)
			)
			(layer "F.Fab")
		)
		(fp_line
			(start 0.67945 -0.3048)
			(end 0.67945 0.3048)
			(stroke
				(width 0.1)
				(type default)
			)
			(layer "F.Fab")
		)
		(fp_line
			(start 0.67945 0.3048)
			(end 0.120396 0.3048)
			(stroke
				(width 0.1)
				(type default)
			)
			(layer "F.Fab")
		)
		(pad "1" smd circle
			(at -0.40005 0)
			(size 0 0)
			(layers "F.Cu" "F.Mask" "F.Paste")
			(net "HSC_D_OC_1")
		)
		(pad "2" smd circle
			(at 0.40005 0)
			(size 0 0)
			(layers "F.Cu" "F.Mask" "F.Paste")
			(net "HSC_D_OC_R")
		)
	)
	(footprint ""
		(layer "F.Cu")
		(at 261.88035 -75.61834 90)
		(property "Reference" "PC1221"
			(at 0 0 90)
			(layer "F.SilkS")
			(hide yes)
			(effects
				(font
					(size 1.27 1.27)
				)
			)
		)
		(property "Value" ""
			(at 0 0 90)
			(layer "F.Fab")
			(effects
				(font
					(size 1.27 1.27)
				)
			)
		)
		(duplicate_pad_numbers_are_jumpers no)
		(fp_line
			(start 0.7874 -0.4064)
			(end 0.7874 0.4064)
			(stroke
				(width 0.1524)
				(type default)
			)
			(layer "F.SilkS")
		)
		(fp_line
			(start -0.7874 -0.4064)
			(end 0.7874 -0.4064)
			(stroke
				(width 0.1524)
				(type default)
			)
			(layer "F.SilkS")
		)
		(fp_line
			(start 0.7874 0.4064)
			(end -0.7874 0.4064)
			(stroke
				(width 0.1524)
				(type default)
			)
			(layer "F.SilkS")
		)
		(fp_line
			(start -0.7874 0.4064)
			(end -0.7874 -0.4064)
			(stroke
				(width 0.1524)
				(type default)
			)
			(layer "F.SilkS")
		)
		(fp_line
			(start -0.12065 -0.305054)
			(end -0.12065 -0.2794)
			(stroke
				(width 0.1)
				(type default)
			)
			(layer "F.Fab")
		)
		(fp_line
			(start -0.67945 -0.305054)
			(end -0.12065 -0.305054)
			(stroke
				(width 0.1)
				(type default)
			)
			(layer "F.Fab")
		)
		(fp_line
			(start 0.67945 -0.3048)
			(end 0.67945 0.3048)
			(stroke
				(width 0.1)
				(type default)
			)
			(layer "F.Fab")
		)
		(fp_line
			(start 0.12065 -0.3048)
			(end 0.67945 -0.3048)
			(stroke
				(width 0.1)
				(type default)
			)
			(layer "F.Fab")
		)
		(fp_line
			(start 0.12065 -0.2794)
			(end 0.12065 -0.3048)
			(stroke
				(width 0.1)
				(type default)
			)
			(layer "F.Fab")
		)
		(fp_line
			(start -0.12065 -0.2794)
			(end 0.12065 -0.2794)
			(stroke
				(width 0.1)
				(type default)
			)
			(layer "F.Fab")
		)
		(fp_line
			(start 0.120396 0.2794)
			(end -0.12065 0.2794)
			(stroke
				(width 0.1)
				(type default)
			)
			(layer "F.Fab")
		)
		(fp_line
			(start -0.12065 0.2794)
			(end -0.12065 0.3048)
			(stroke
				(width 0.1)
				(type default)
			)
			(layer "F.Fab")
		)
		(fp_line
			(start 0.67945 0.3048)
			(end 0.120396 0.3048)
			(stroke
				(width 0.1)
				(type default)
			)
			(layer "F.Fab")
		)
		(fp_line
			(start 0.120396 0.3048)
			(end 0.120396 0.2794)
			(stroke
				(width 0.1)
				(type default)
			)
			(layer "F.Fab")
		)
		(fp_line
			(start -0.12065 0.3048)
			(end -0.67945 0.3048)
			(stroke
				(width 0.1)
				(type default)
			)
			(layer "F.Fab")
		)
		(fp_line
			(start -0.67945 0.3048)
			(end -0.67945 -0.305054)
			(stroke
				(width 0.1)
				(type default)
			)
			(layer "F.Fab")
		)
		(pad "1" smd circle
			(at -0.40005 0 90)
			(size 0 0)
			(layers "F.Cu" "F.Mask" "F.Paste")
			(net "P1V05_PCH_AUX_REF")
		)
		(pad "2" smd circle
			(at 0.40005 0 90)
			(size 0 0)
			(layers "F.Cu" "F.Mask" "F.Paste")
			(net "SH_P1V05_PCH_AUX_N")
		)
	)
	(footprint ""
		(layer "F.Cu")
		(at 105.312464 -238.162592 90)
		(property "Reference" "C310"
			(at 0 0 90)
			(layer "F.SilkS")
			(hide yes)
			(effects
				(font
					(size 1.27 1.27)
				)
			)
		)
		(property "Value" ""
			(at 0 0 90)
			(layer "F.Fab")
			(effects
				(font
					(size 1.27 1.27)
				)
			)
		)
		(duplicate_pad_numbers_are_jumpers no)
		(fp_line
			(start 0.7874 -0.4064)
			(end 0.7874 0.4064)
			(stroke
				(width 0.1524)
				(type default)
			)
			(layer "F.SilkS")
		)
		(fp_line
			(start -0.7874 -0.4064)
			(end 0.7874 -0.4064)
			(stroke
				(width 0.1524)
				(type default)
			)
			(layer "F.SilkS")
		)
		(fp_line
			(start 0.7874 0.4064)
			(end -0.7874 0.4064)
			(stroke
				(width 0.1524)
				(type default)
			)
			(layer "F.SilkS")
		)
		(fp_line
			(start -0.7874 0.4064)
			(end -0.7874 -0.4064)
			(stroke
				(width 0.1524)
				(type default)
			)
			(layer "F.SilkS")
		)
		(fp_line
			(start -0.12065 -0.305054)
			(end -0.12065 -0.2794)
			(stroke
				(width 0.1)
				(type default)
			)
			(layer "F.Fab")
		)
		(fp_line
			(start -0.67945 -0.305054)
			(end -0.12065 -0.305054)
			(stroke
				(width 0.1)
				(type default)
			)
			(layer "F.Fab")
		)
		(fp_line
			(start 0.67945 -0.3048)
			(end 0.67945 0.3048)
			(stroke
				(width 0.1)
				(type default)
			)
			(layer "F.Fab")
		)
		(fp_line
			(start 0.12065 -0.3048)
			(end 0.67945 -0.3048)
			(stroke
				(width 0.1)
				(type default)
			)
			(layer "F.Fab")
		)
		(fp_line
			(start 0.12065 -0.2794)
			(end 0.12065 -0.3048)
			(stroke
				(width 0.1)
				(type default)
			)
			(layer "F.Fab")
		)
		(fp_line
			(start -0.12065 -0.2794)
			(end 0.12065 -0.2794)
			(stroke
				(width 0.1)
				(type default)
			)
			(layer "F.Fab")
		)
		(fp_line
			(start 0.120396 0.2794)
			(end -0.12065 0.2794)
			(stroke
				(width 0.1)
				(type default)
			)
			(layer "F.Fab")
		)
		(fp_line
			(start -0.12065 0.2794)
			(end -0.12065 0.3048)
			(stroke
				(width 0.1)
				(type default)
			)
			(layer "F.Fab")
		)
		(fp_line
			(start 0.67945 0.3048)
			(end 0.120396 0.3048)
			(stroke
				(width 0.1)
				(type default)
			)
			(layer "F.Fab")
		)
		(fp_line
			(start 0.120396 0.3048)
			(end 0.120396 0.2794)
			(stroke
				(width 0.1)
				(type default)
			)
			(layer "F.Fab")
		)
		(fp_line
			(start -0.12065 0.3048)
			(end -0.67945 0.3048)
			(stroke
				(width 0.1)
				(type default)
			)
			(layer "F.Fab")
		)
		(fp_line
			(start -0.67945 0.3048)
			(end -0.67945 -0.305054)
			(stroke
				(width 0.1)
				(type default)
			)
			(layer "F.Fab")
		)
		(pad "1" smd circle
			(at -0.40005 0 90)
			(size 0 0)
			(layers "F.Cu" "F.Mask" "F.Paste")
			(net "PVNN_MAIN_CPU1")
		)
		(pad "2" smd circle
			(at 0.40005 0 90)
			(size 0 0)
			(layers "F.Cu" "F.Mask" "F.Paste")
			(net "GND")
		)
	)
	(footprint ""
		(layer "F.Cu")
		(at 250.65482 2.921 180)
		(property "Reference" "J85"
			(at -4.26085 -1.143 90)
			(unlocked yes)
			(layer "F.SilkS")
			(effects
				(font
					(size 0.7874 0.5842)
					(thickness 0.1524)
				)
				(justify left)
			)
		)
		(property "Value" ""
			(at 0 0 180)
			(layer "F.Fab")
			(effects
				(font
					(size 1.27 1.27)
				)
			)
		)
		(duplicate_pad_numbers_are_jumpers no)
		(fp_line
			(start 1.2192 2.1082)
			(end -1.2192 2.1082)
			(stroke
				(width 0.1524)
				(type default)
			)
			(layer "F.SilkS")
		)
		(fp_line
			(start 1.2192 -2.1082)
			(end 1.2192 2.1082)
			(stroke
				(width 0.1524)
				(type default)
			)
			(layer "F.SilkS")
		)
		(fp_line
			(start -1.2192 2.1082)
			(end -1.2192 -2.1082)
			(stroke
				(width 0.1524)
				(type default)
			)
			(layer "F.SilkS")
		)
		(fp_line
			(start -1.2192 -2.1082)
			(end 1.2192 -2.1082)
			(stroke
				(width 0.1524)
				(type default)
			)
			(layer "F.SilkS")
		)
		(pad "" np_thru_hole circle
			(at -2.8829 -1.27 90)
			(size 1.0414 1.0414)
			(drill 1.0414)
			(layers "*.Cu" "*.Mask")
			(clearance 0.381)
			(thermal_gap 0.381)
		)
		(pad "" np_thru_hole circle
			(at -2.8829 1.27 90)
			(size 1.0414 1.0414)
			(drill 1.0414)
			(layers "*.Cu" "*.Mask")
			(clearance 0.381)
			(thermal_gap 0.381)
		)
		(pad "" np_thru_hole circle
			(at 3.4671 -1.27 90)
			(size 1.0414 1.0414)
			(drill 1.0414)
			(layers "*.Cu" "*.Mask")
			(clearance 0.381)
			(thermal_gap 0.381)
		)
		(pad "" np_thru_hole circle
			(at 3.4671 1.27 90)
			(size 1.0414 1.0414)
			(drill 1.0414)
			(layers "*.Cu" "*.Mask")
			(clearance 0.381)
			(thermal_gap 0.381)
		)
		(pad "1" smd rect
			(at 0.8255 -0.249936 90)
			(size 0.3048 0.508)
			(layers "F.Cu" "F.Mask" "F.Paste")
			(net "DELTA_L_85_10INCH_IN3_DN")
		)
		(pad "2" smd rect
			(at 0.8255 0.249936 90)
			(size 0.3048 0.508)
			(layers "F.Cu" "F.Mask" "F.Paste")
			(net "DELTA_L_85_10INCH_IN3_DP")
		)
		(pad "3" smd circle
			(at 0 0 180)
			(size 0 0)
			(layers "F.Cu" "F.Mask" "F.Paste")
			(net "DELTA_L_GND_1")
		)
		(zone
			(layer "F.Cu")
			(hatch none 0.5)
			(connect_pads
				(clearance 0)
			)
			(min_thickness 0.25)
			(keepout
				(tracks not_allowed)
				(vias allowed)
				(pads allowed)
				(copperpour not_allowed)
				(footprints allowed)
			)
			(placement
				(enabled no)
				(sheetname "")
			)
			(fill
				(thermal_gap 0.5)
				(thermal_bridge_width 0.5)
				(island_removal_mode 0)
			)
			(polygon
				(pts
					(xy 249.53722 3.46964) (xy 249.53722 3.374136) (xy 250.13412 3.374136) (xy 250.13412 2.967736)
					(xy 249.53722 2.967736) (xy 249.53722 2.874264) (xy 250.13412 2.874264) (xy 250.13412 2.467864)
					(xy 249.53722 2.467864) (xy 249.53722 2.37236) (xy 250.23572 2.37236) (xy 250.23572 3.46964)
				)
			)
		)
		(zone
			(layers "F.Cu" "B.Cu" "In1.Cu" "In2.Cu" "In3.Cu" "In4.Cu" "In5.Cu" "In6.Cu"
				"In7.Cu" "In8.Cu" "In9.Cu" "In10.Cu" "In11.Cu" "In12.Cu" "In13.Cu" "In14.Cu"
				"In15.Cu" "In16.Cu"
			)
			(hatch none 0.5)
			(connect_pads
				(clearance 0)
			)
			(min_thickness 0.25)
			(keepout
				(tracks not_allowed)
				(vias allowed)
				(pads allowed)
				(copperpour not_allowed)
				(footprints allowed)
			)
			(placement
				(enabled no)
				(sheetname "")
			)
			(fill
				(thermal_gap 0.5)
				(thermal_bridge_width 0.5)
				(island_removal_mode 0)
			)
			(polygon
				(pts
					(arc
						(start 248.11482 1.651)
						(mid 246.26062 1.651)
						(end 248.11482 1.651)
					)
				)
			)
		)
		(zone
			(layers "F.Cu" "B.Cu" "In1.Cu" "In2.Cu" "In3.Cu" "In4.Cu" "In5.Cu" "In6.Cu"
				"In7.Cu" "In8.Cu" "In9.Cu" "In10.Cu" "In11.Cu" "In12.Cu" "In13.Cu" "In14.Cu"
				"In15.Cu" "In16.Cu"
			)
			(hatch none 0.5)
			(connect_pads
				(clearance 0)
			)
			(min_thickness 0.25)
			(keepout
				(tracks not_allowed)
				(vias allowed)
				(pads allowed)
				(copperpour not_allowed)
				(footprints allowed)
			)
			(placement
				(enabled no)
				(sheetname "")
			)
			(fill
				(thermal_gap 0.5)
				(thermal_bridge_width 0.5)
				(island_removal_mode 0)
			)
			(polygon
				(pts
					(arc
						(start 248.11482 4.191)
						(mid 246.26062 4.191)
						(end 248.11482 4.191)
					)
				)
			)
		)
		(zone
			(layers "F.Cu" "B.Cu" "In1.Cu" "In2.Cu" "In3.Cu" "In4.Cu" "In5.Cu" "In6.Cu"
				"In7.Cu" "In8.Cu" "In9.Cu" "In10.Cu" "In11.Cu" "In12.Cu" "In13.Cu" "In14.Cu"
				"In15.Cu" "In16.Cu"
			)
			(hatch none 0.5)
			(connect_pads
				(clearance 0)
			)
			(min_thickness 0.25)
			(keepout
				(tracks not_allowed)
				(vias allowed)
				(pads allowed)
				(copperpour not_allowed)
				(footprints allowed)
			)
			(placement
				(enabled no)
				(sheetname "")
			)
			(fill
				(thermal_gap 0.5)
				(thermal_bridge_width 0.5)
				(island_removal_mode 0)
			)
			(polygon
				(pts
					(arc
						(start 254.46482 1.651)
						(mid 252.61062 1.651)
						(end 254.46482 1.651)
					)
				)
			)
		)
		(zone
			(layers "F.Cu" "B.Cu" "In1.Cu" "In2.Cu" "In3.Cu" "In4.Cu" "In5.Cu" "In6.Cu"
				"In7.Cu" "In8.Cu" "In9.Cu" "In10.Cu" "In11.Cu" "In12.Cu" "In13.Cu" "In14.Cu"
				"In15.Cu" "In16.Cu"
			)
			(hatch none 0.5)
			(connect_pads
				(clearance 0)
			)
			(min_thickness 0.25)
			(keepout
				(tracks not_allowed)
				(vias allowed)
				(pads allowed)
				(copperpour not_allowed)
				(footprints allowed)
			)
			(placement
				(enabled no)
				(sheetname "")
			)
			(fill
				(thermal_gap 0.5)
				(thermal_bridge_width 0.5)
				(island_removal_mode 0)
			)
			(polygon
				(pts
					(arc
						(start 254.46482 4.191)
						(mid 252.61062 4.191)
						(end 254.46482 4.191)
					)
				)
			)
		)
	)
	(footprint ""
		(layer "F.Cu")
		(at 449.38442 -77.829918 90)
		(property "Reference" "PC569"
			(at 0 0 90)
			(layer "F.SilkS")
			(hide yes)
			(effects
				(font
					(size 1.27 1.27)
				)
			)
		)
		(property "Value" ""
			(at 0 0 90)
			(layer "F.Fab")
			(effects
				(font
					(size 1.27 1.27)
				)
			)
		)
		(duplicate_pad_numbers_are_jumpers no)
		(fp_line
			(start 0.7874 -0.4064)
			(end 0.7874 0.4064)
			(stroke
				(width 0.1524)
				(type default)
			)
			(layer "F.SilkS")
		)
		(fp_line
			(start -0.7874 -0.4064)
			(end 0.7874 -0.4064)
			(stroke
				(width 0.1524)
				(type default)
			)
			(layer "F.SilkS")
		)
		(fp_line
			(start 0.7874 0.4064)
			(end -0.7874 0.4064)
			(stroke
				(width 0.1524)
				(type default)
			)
			(layer "F.SilkS")
		)
		(fp_line
			(start -0.7874 0.4064)
			(end -0.7874 -0.4064)
			(stroke
				(width 0.1524)
				(type default)
			)
			(layer "F.SilkS")
		)
		(fp_line
			(start -0.12065 -0.305054)
			(end -0.12065 -0.2794)
			(stroke
				(width 0.1)
				(type default)
			)
			(layer "F.Fab")
		)
		(fp_line
			(start -0.67945 -0.305054)
			(end -0.12065 -0.305054)
			(stroke
				(width 0.1)
				(type default)
			)
			(layer "F.Fab")
		)
		(fp_line
			(start 0.67945 -0.3048)
			(end 0.67945 0.3048)
			(stroke
				(width 0.1)
				(type default)
			)
			(layer "F.Fab")
		)
		(fp_line
			(start 0.12065 -0.3048)
			(end 0.67945 -0.3048)
			(stroke
				(width 0.1)
				(type default)
			)
			(layer "F.Fab")
		)
		(fp_line
			(start 0.12065 -0.2794)
			(end 0.12065 -0.3048)
			(stroke
				(width 0.1)
				(type default)
			)
			(layer "F.Fab")
		)
		(fp_line
			(start -0.12065 -0.2794)
			(end 0.12065 -0.2794)
			(stroke
				(width 0.1)
				(type default)
			)
			(layer "F.Fab")
		)
		(fp_line
			(start 0.120396 0.2794)
			(end -0.12065 0.2794)
			(stroke
				(width 0.1)
				(type default)
			)
			(layer "F.Fab")
		)
		(fp_line
			(start -0.12065 0.2794)
			(end -0.12065 0.3048)
			(stroke
				(width 0.1)
				(type default)
			)
			(layer "F.Fab")
		)
		(fp_line
			(start 0.67945 0.3048)
			(end 0.120396 0.3048)
			(stroke
				(width 0.1)
				(type default)
			)
			(layer "F.Fab")
		)
		(fp_line
			(start 0.120396 0.3048)
			(end 0.120396 0.2794)
			(stroke
				(width 0.1)
				(type default)
			)
			(layer "F.Fab")
		)
		(fp_line
			(start -0.12065 0.3048)
			(end -0.67945 0.3048)
			(stroke
				(width 0.1)
				(type default)
			)
			(layer "F.Fab")
		)
		(fp_line
			(start -0.67945 0.3048)
			(end -0.67945 -0.305054)
			(stroke
				(width 0.1)
				(type default)
			)
			(layer "F.Fab")
		)
		(pad "1" smd circle
			(at -0.40005 0 90)
			(size 0 0)
			(layers "F.Cu" "F.Mask" "F.Paste")
			(net "P3V3_AUX_FB")
		)
		(pad "2" smd circle
			(at 0.40005 0 90)
			(size 0 0)
			(layers "F.Cu" "F.Mask" "F.Paste")
			(net "P3V3_AUX")
		)
	)
)
